(kicad_pcb
	(version 20241229)
	(generator "pcbnew")
	(generator_version "9.0")
	(general
		(thickness 1.6296)
		(legacy_teardrops no)
	)
	(paper "A3")
	(title_block
		(title "Thunderbolt to 10GbE adapter")
		(date "2026-04-21")
		(rev "1.1.0")
		(company "Antmicro Ltd")
		(comment 1 "www.antmicro.com")
		(comment 9 "footprints 188-191 of 703")
	)
	(layers
		(0 "F.Cu" signal)
		(4 "In1.Cu" signal)
		(6 "In2.Cu" signal)
		(8 "In3.Cu" signal)
		(10 "In4.Cu" signal)
		(12 "In5.Cu" signal)
		(14 "In6.Cu" signal)
		(2 "B.Cu" signal)
		(9 "F.Adhes" user "F.Adhesive")
		(11 "B.Adhes" user "B.Adhesive")
		(13 "F.Paste" user)
		(15 "B.Paste" user)
		(5 "F.SilkS" user "F.Silkscreen")
		(7 "B.SilkS" user "B.Silkscreen")
		(1 "F.Mask" user)
		(3 "B.Mask" user)
		(17 "Dwgs.User" user "User.Drawings")
		(19 "Cmts.User" user "User.Comments")
		(21 "Eco1.User" user "User.Eco1")
		(23 "Eco2.User" user "User.Eco2")
		(25 "Edge.Cuts" user)
		(27 "Margin" user)
		(31 "F.CrtYd" user "F.Courtyard")
		(29 "B.CrtYd" user "B.Courtyard")
		(35 "F.Fab" user)
		(33 "B.Fab" user)
	)
	(footprint "antmicro-footprints:C_0402_1005Metric"
		(layer "F.Cu")
		(at 138 72.25)
		(descr "Capacitor SMD 0402")
		(tags "capacitor SMD 0402")
		(property "Reference" "C270"
			(at -3.8 0.45 0)
			(layer "F.SilkS")
			(effects
				(font
					(size 0.7 0.7)
					(thickness 0.15)
				)
				(justify left bottom)
			)
		)
		(property "Value" "C_220n_16V_0402"
			(at -1.022927 2.155213 0)
			(layer "F.Fab")
			(effects
				(font
					(size 0.7 0.7)
					(thickness 0.15)
				)
				(justify left bottom)
			)
		)
		(property "Datasheet" "https://www.murata.com/products/productdetail?partno=GRM155R71C224KA12%23"
			(at 0 0 0)
			(layer "F.Fab")
			(hide yes)
			(effects
				(font
					(size 1.27 1.27)
					(thickness 0.15)
				)
			)
		)
		(property "Description" "SMD Multilayer Ceramic Capacitor, 0.22 µF, 16 V, 0402 [1005 Metric], ± 10%, X7R, GRM Series"
			(at 0 0 0)
			(layer "F.Fab")
			(hide yes)
			(effects
				(font
					(size 1.27 1.27)
					(thickness 0.15)
				)
			)
		)
		(property "MPN" "GRM155R71C224KA12D"
			(at 0 0 0)
			(unlocked yes)
			(layer "F.Fab")
			(hide yes)
			(effects
				(font
					(size 1 1)
					(thickness 0.15)
				)
			)
		)
		(property "Manufacturer" "Murata"
			(at 0 0 0)
			(unlocked yes)
			(layer "F.Fab")
			(hide yes)
			(effects
				(font
					(size 1 1)
					(thickness 0.15)
				)
			)
		)
		(property "License" "Apache-2.0"
			(at 0 0 0)
			(unlocked yes)
			(layer "F.Fab")
			(hide yes)
			(effects
				(font
					(size 1 1)
					(thickness 0.15)
				)
			)
		)
		(property "Author" "Antmicro"
			(at 0 0 0)
			(unlocked yes)
			(layer "F.Fab")
			(hide yes)
			(effects
				(font
					(size 1 1)
					(thickness 0.15)
				)
			)
		)
		(property "Val" "220n"
			(at 0 0 0)
			(unlocked yes)
			(layer "F.Fab")
			(hide yes)
			(effects
				(font
					(size 1 1)
					(thickness 0.15)
				)
			)
		)
		(property "Voltage" "16V"
			(at 0 0 0)
			(unlocked yes)
			(layer "F.Fab")
			(hide yes)
			(effects
				(font
					(size 1 1)
					(thickness 0.15)
				)
			)
		)
		(property "Dielectric" "X7R"
			(at 0 0 0)
			(unlocked yes)
			(layer "F.Fab")
			(hide yes)
			(effects
				(font
					(size 1 1)
					(thickness 0.15)
				)
			)
		)
		(sheetname "/X710-AT2 PCIe/")
		(sheetfile "x710-at2-pcie.kicad_sch")
		(attr smd)
		(fp_rect
			(start -0.925 -0.47)
			(end 0.925 0.47)
			(stroke
				(width 0.05)
				(type default)
			)
			(fill no)
			(layer "F.CrtYd")
		)
		(fp_line
			(start -0.494 -0.25)
			(end 0.504 -0.25)
			(stroke
				(width 0.15)
				(type solid)
			)
			(layer "F.Fab")
		)
		(fp_line
			(start -0.494 0.248)
			(end -0.494 -0.25)
			(stroke
				(width 0.15)
				(type solid)
			)
			(layer "F.Fab")
		)
		(fp_line
			(start 0.504 -0.25)
			(end 0.504 0.248)
			(stroke
				(width 0.15)
				(type solid)
			)
			(layer "F.Fab")
		)
		(fp_line
			(start 0.504 0.248)
			(end -0.494 0.248)
			(stroke
				(width 0.15)
				(type solid)
			)
			(layer "F.Fab")
		)
		(fp_text user "Author: Antmicro"
			(at -0.939 3.399 0)
			(layer "F.Fab")
			(effects
				(font
					(size 0.7 0.7)
					(thickness 0.15)
				)
				(justify left bottom)
			)
		)
		(fp_text user "${REFERENCE}"
			(at -0.939 4.599 0)
			(layer "F.Fab")
			(effects
				(font
					(size 0.7 0.7)
					(thickness 0.15)
				)
				(justify left bottom)
			)
		)
		(fp_text user "License: Apache-2.0"
			(at -0.939 5.799 0)
			(layer "F.Fab")
			(effects
				(font
					(size 0.7 0.7)
					(thickness 0.15)
				)
				(justify left bottom)
			)
		)
		(pad "1" smd roundrect
			(at -0.48 0)
			(size 0.59 0.64)
			(layers "F.Cu" "F.Mask" "F.Paste")
			(roundrect_rratio 0.25)
			(net 596 "/TB Controller/PCIex4.TX0+")
			(pintype "passive")
		)
		(pad "2" smd roundrect
			(at 0.48 0)
			(size 0.59 0.64)
			(layers "F.Cu" "F.Mask" "F.Paste")
			(roundrect_rratio 0.25)
			(net 27 "/X710-AT2 PCIe/PCIe_{x4}_AC.TX0+")
			(pintype "passive")
		)
	)
	(footprint "antmicro-footprints:C_0402_1005Metric"
		(layer "F.Cu")
		(at 126.4 94.9)
		(descr "Capacitor SMD 0402")
		(tags "capacitor SMD 0402")
		(property "Reference" "C41"
			(at -0.9 -0.6 0)
			(layer "F.SilkS")
			(effects
				(font
					(size 0.7 0.7)
					(thickness 0.15)
				)
				(justify left bottom)
			)
		)
		(property "Value" "C_100n_0402"
			(at -1.022927 2.155213 0)
			(layer "F.Fab")
			(effects
				(font
					(size 0.7 0.7)
					(thickness 0.15)
				)
				(justify left bottom)
			)
		)
		(property "Datasheet" "https://www.murata.com/products/productdetail?partno=GRM155R61H104KE14%23"
			(at 0 0 0)
			(layer "F.Fab")
			(hide yes)
			(effects
				(font
					(size 1.27 1.27)
					(thickness 0.15)
				)
			)
		)
		(property "Description" "SMD Multilayer Ceramic Capacitor, 0.1 µF, 50 V, 0402 [1005 Metric], ± 10%, X5R, GRM Series"
			(at 0 0 0)
			(layer "F.Fab")
			(hide yes)
			(effects
				(font
					(size 1.27 1.27)
					(thickness 0.15)
				)
			)
		)
		(property "MPN" "GRM155R61H104KE14D"
			(at 0 0 0)
			(unlocked yes)
			(layer "F.Fab")
			(hide yes)
			(effects
				(font
					(size 1 1)
					(thickness 0.15)
				)
			)
		)
		(property "Manufacturer" "Murata"
			(at 0 0 0)
			(unlocked yes)
			(layer "F.Fab")
			(hide yes)
			(effects
				(font
					(size 1 1)
					(thickness 0.15)
				)
			)
		)
		(property "License" "Apache-2.0"
			(at 0 0 0)
			(unlocked yes)
			(layer "F.Fab")
			(hide yes)
			(effects
				(font
					(size 1 1)
					(thickness 0.15)
				)
			)
		)
		(property "Val" "100n"
			(at 0 0 0)
			(unlocked yes)
			(layer "F.Fab")
			(hide yes)
			(effects
				(font
					(size 1 1)
					(thickness 0.15)
				)
			)
		)
		(property "Voltage" "50V"
			(at 0 0 0)
			(unlocked yes)
			(layer "F.Fab")
			(hide yes)
			(effects
				(font
					(size 1 1)
					(thickness 0.15)
				)
			)
		)
		(property "Dielectric" "X5R"
			(at 0 0 0)
			(unlocked yes)
			(layer "F.Fab")
			(hide yes)
			(effects
				(font
					(size 1 1)
					(thickness 0.15)
				)
			)
		)
		(property "Author" "Antmicro"
			(at 0 0 0)
			(unlocked yes)
			(layer "F.Fab")
			(hide yes)
			(effects
				(font
					(size 1 1)
					(thickness 0.15)
				)
			)
		)
		(sheetname "/TB Controller/")
		(sheetfile "tb.kicad_sch")
		(attr smd)
		(fp_rect
			(start -0.925 -0.47)
			(end 0.925 0.47)
			(stroke
				(width 0.05)
				(type default)
			)
			(fill no)
			(layer "F.CrtYd")
		)
		(fp_line
			(start -0.494 -0.25)
			(end 0.504 -0.25)
			(stroke
				(width 0.15)
				(type solid)
			)
			(layer "F.Fab")
		)
		(fp_line
			(start -0.494 0.248)
			(end -0.494 -0.25)
			(stroke
				(width 0.15)
				(type solid)
			)
			(layer "F.Fab")
		)
		(fp_line
			(start 0.504 -0.25)
			(end 0.504 0.248)
			(stroke
				(width 0.15)
				(type solid)
			)
			(layer "F.Fab")
		)
		(fp_line
			(start 0.504 0.248)
			(end -0.494 0.248)
			(stroke
				(width 0.15)
				(type solid)
			)
			(layer "F.Fab")
		)
		(fp_text user "Author: Antmicro"
			(at -0.939 3.399 0)
			(layer "F.Fab")
			(effects
				(font
					(size 0.7 0.7)
					(thickness 0.15)
				)
				(justify left bottom)
			)
		)
		(fp_text user "${REFERENCE}"
			(at -0.939 4.599 0)
			(layer "F.Fab")
			(effects
				(font
					(size 0.7 0.7)
					(thickness 0.15)
				)
				(justify left bottom)
			)
		)
		(fp_text user "License: Apache-2.0"
			(at -0.939 5.799 0)
			(layer "F.Fab")
			(effects
				(font
					(size 0.7 0.7)
					(thickness 0.15)
				)
				(justify left bottom)
			)
		)
		(pad "1" smd roundrect
			(at -0.48 0)
			(size 0.59 0.64)
			(layers "F.Cu" "F.Mask" "F.Paste")
			(roundrect_rratio 0.25)
			(net 23 "GND")
			(pintype "passive")
		)
		(pad "2" smd roundrect
			(at 0.48 0)
			(size 0.59 0.64)
			(layers "F.Cu" "F.Mask" "F.Paste")
			(roundrect_rratio 0.25)
			(net 57 "+3V3_TB")
			(pintype "passive")
		)
	)
	(footprint "antmicro-footprints:SW_DS04-254-1-01BK-SMT"
		(layer "F.Cu")
		(at 118 59.5 -90)
		(property "Reference" "SW1"
			(at -2.25 -3 270)
			(layer "F.SilkS")
			(effects
				(font
					(size 0.7 0.7)
					(thickness 0.15)
				)
				(justify left bottom)
			)
		)
		(property "Value" "SW_DS04-254-1-01BK-SMT"
			(at 0 3 270)
			(layer "F.Fab")
			(effects
				(font
					(size 0.7 0.7)
					(thickness 0.15)
				)
				(justify left bottom)
			)
		)
		(property "Datasheet" "https://www.mouser.com/datasheet/2/670/ds04_254_smt-1777718.pdf"
			(at 0 0 270)
			(layer "F.Fab")
			(hide yes)
			(effects
				(font
					(size 1.27 1.27)
					(thickness 0.15)
				)
			)
		)
		(property "Description" "Slide switch"
			(at 0 0 270)
			(layer "F.Fab")
			(hide yes)
			(effects
				(font
					(size 1.27 1.27)
					(thickness 0.15)
				)
			)
		)
		(property "MPN" "DS04-254-1-01BK-SMT"
			(at 0 0 270)
			(unlocked yes)
			(layer "F.Fab")
			(hide yes)
			(effects
				(font
					(size 1 1)
					(thickness 0.15)
				)
			)
		)
		(property "Manufacturer" "CUI Inc"
			(at 0 0 270)
			(unlocked yes)
			(layer "F.Fab")
			(hide yes)
			(effects
				(font
					(size 1 1)
					(thickness 0.15)
				)
			)
		)
		(property "Author" "Antmicro"
			(at 0 0 270)
			(unlocked yes)
			(layer "F.Fab")
			(hide yes)
			(effects
				(font
					(size 1 1)
					(thickness 0.15)
				)
			)
		)
		(property "License" "Apache-2.0"
			(at 0 0 270)
			(unlocked yes)
			(layer "F.Fab")
			(hide yes)
			(effects
				(font
					(size 1 1)
					(thickness 0.15)
				)
			)
		)
		(property ki_fp_filters "SW?DIP?x1*")
		(sheetname "/X710-AT2 RSVD/")
		(sheetfile "x710-at2-rsvd.kicad_sch")
		(attr smd dnp)
		(fp_rect
			(start -3.3 -2)
			(end 3.3 2)
			(stroke
				(width 0.15)
				(type solid)
			)
			(fill no)
			(layer "F.SilkS")
		)
		(fp_rect
			(start -5.25 -2.025)
			(end 5.25 2.025)
			(stroke
				(width 0.05)
				(type solid)
			)
			(fill no)
			(layer "F.CrtYd")
		)
		(fp_rect
			(start -3.1 -1.8)
			(end 3.1 1.8)
			(stroke
				(width 0.15)
				(type solid)
			)
			(fill no)
			(layer "F.Fab")
		)
		(fp_text user "Author: Antmicro"
			(at -5.25 5.6 270)
			(layer "F.Fab")
			(effects
				(font
					(size 0.7 0.7)
					(thickness 0.15)
				)
				(justify left bottom)
			)
		)
		(fp_text user "License: Apache-2.0"
			(at -5.25 6.799 270)
			(layer "F.Fab")
			(effects
				(font
					(size 0.7 0.7)
					(thickness 0.15)
				)
				(justify left bottom)
			)
		)
		(fp_text user "${REFERENCE}"
			(at -5.25 4.4 270)
			(layer "F.Fab")
			(effects
				(font
					(size 0.7 0.7)
					(thickness 0.15)
				)
				(justify left bottom)
			)
		)
		(pad "1" smd rect
			(at -4.472 0.038 270)
			(size 1.5 1.1)
			(layers "F.Cu" "F.Mask" "F.Paste")
			(net 86 "/X710-AT2 RSVD/DEBUG_EN")
			(pintype "passive")
		)
		(pad "2" smd rect
			(at 4.428 0.038 90)
			(size 1.5 1.1)
			(layers "F.Cu" "F.Mask" "F.Paste")
			(net 7 "+3V3")
			(pintype "passive")
		)
	)
	(footprint "antmicro-footprints:C_0402_1005Metric"
		(layer "F.Cu")
		(at 118 140.2)
		(descr "Capacitor SMD 0402")
		(tags "capacitor SMD 0402")
		(property "Reference" "C5"
			(at 1 0.4 0)
			(layer "F.SilkS")
			(effects
				(font
					(size 0.7 0.7)
					(thickness 0.15)
				)
				(justify left bottom)
			)
		)
		(property "Value" "C_4u7_25V_0402"
			(at -1.022927 2.155213 0)
			(layer "F.Fab")
			(effects
				(font
					(size 0.7 0.7)
					(thickness 0.15)
				)
				(justify left bottom)
			)
		)
		(property "Datasheet" "https://www.murata.com/products/productdetail?partno=GRM155C61E475ME15%23"
			(at 0 0 0)
			(layer "F.Fab")
			(hide yes)
			(effects
				(font
					(size 1.27 1.27)
					(thickness 0.15)
				)
			)
		)
		(property "Description" "SMD Multilayer Ceramic Capacitor"
			(at 0 0 0)
			(layer "F.Fab")
			(hide yes)
			(effects
				(font
					(size 1.27 1.27)
					(thickness 0.15)
				)
			)
		)
		(property "MPN" "GRM155C61E475ME15J"
			(at 0 0 0)
			(unlocked yes)
			(layer "F.Fab")
			(hide yes)
			(effects
				(font
					(size 1 1)
					(thickness 0.15)
				)
			)
		)
		(property "Manufacturer" "Murata"
			(at 0 0 0)
			(unlocked yes)
			(layer "F.Fab")
			(hide yes)
			(effects
				(font
					(size 1 1)
					(thickness 0.15)
				)
			)
		)
		(property "License" "Apache-2.0"
			(at 0 0 0)
			(unlocked yes)
			(layer "F.Fab")
			(hide yes)
			(effects
				(font
					(size 1 1)
					(thickness 0.15)
				)
			)
		)
		(property "Author" "Antmicro"
			(at 0 0 0)
			(unlocked yes)
			(layer "F.Fab")
			(hide yes)
			(effects
				(font
					(size 1 1)
					(thickness 0.15)
				)
			)
		)
		(property "Val" "4u7"
			(at 0 0 0)
			(unlocked yes)
			(layer "F.Fab")
			(hide yes)
			(effects
				(font
					(size 1 1)
					(thickness 0.15)
				)
			)
		)
		(property "Voltage" "25V"
			(at 0 0 0)
			(unlocked yes)
			(layer "F.Fab")
			(hide yes)
			(effects
				(font
					(size 1 1)
					(thickness 0.15)
				)
			)
		)
		(property "Dielectric" "X5S"
			(at 0 0 0)
			(unlocked yes)
			(layer "F.Fab")
			(hide yes)
			(effects
				(font
					(size 1 1)
					(thickness 0.15)
				)
			)
		)
		(sheetname "/USB-C connector/")
		(sheetfile "USB-C_connector.kicad_sch")
		(attr smd)
		(fp_rect
			(start -0.925 -0.47)
			(end 0.925 0.47)
			(stroke
				(width 0.05)
				(type default)
			)
			(fill no)
			(layer "F.CrtYd")
		)
		(fp_line
			(start -0.494 -0.25)
			(end 0.504 -0.25)
			(stroke
				(width 0.15)
				(type solid)
			)
			(layer "F.Fab")
		)
		(fp_line
			(start -0.494 0.248)
			(end -0.494 -0.25)
			(stroke
				(width 0.15)
				(type solid)
			)
			(layer "F.Fab")
		)
		(fp_line
			(start 0.504 -0.25)
			(end 0.504 0.248)
			(stroke
				(width 0.15)
				(type solid)
			)
			(layer "F.Fab")
		)
		(fp_line
			(start 0.504 0.248)
			(end -0.494 0.248)
			(stroke
				(width 0.15)
				(type solid)
			)
			(layer "F.Fab")
		)
		(fp_text user "${REFERENCE}"
			(at -0.939 4.599 0)
			(layer "F.Fab")
			(effects
				(font
					(size 0.7 0.7)
					(thickness 0.15)
				)
				(justify left bottom)
			)
		)
		(fp_text user "License: Apache-2.0"
			(at -0.939 5.799 0)
			(layer "F.Fab")
			(effects
				(font
					(size 0.7 0.7)
					(thickness 0.15)
				)
				(justify left bottom)
			)
		)
		(fp_text user "Author: Antmicro"
			(at -0.939 3.399 0)
			(layer "F.Fab")
			(effects
				(font
					(size 0.7 0.7)
					(thickness 0.15)
				)
				(justify left bottom)
			)
		)
		(pad "1" smd roundrect
			(at -0.48 0)
			(size 0.59 0.64)
			(layers "F.Cu" "F.Mask" "F.Paste")
			(roundrect_rratio 0.25)
			(net 23 "GND")
			(pintype "passive")
		)
		(pad "2" smd roundrect
			(at 0.48 0)
			(size 0.59 0.64)
			(layers "F.Cu" "F.Mask" "F.Paste")
			(roundrect_rratio 0.25)
			(net 53 "+5V_USB")
			(pintype "passive")
		)
	)
)
